(kicad_pcb
	(version 20260206)
	(generator "pcbnew")
	(generator_version "10.0")
	(general
		(thickness 1.6)
		(legacy_teardrops no)
	)
	(paper "A4")
	(title_block
		(title "12092022_DA0F0TFB6D0_F0T_FAN_BOARD_MP5048_D_brd_v02_OCP.brd")
		(comment 1 "Grand Teton / footprints 504-509 of 924")
	)
	(layers
		(0 "F.Cu" signal "TOP")
		(4 "In1.Cu" signal "GND")
		(6 "In2.Cu" signal "IN1")
		(8 "In3.Cu" signal "IN2")
		(10 "In4.Cu" signal "GND1")
		(2 "B.Cu" signal "BOTTOM")
		(9 "F.Adhes" user "F.Adhesive")
		(11 "B.Adhes" user "B.Adhesive")
		(13 "F.Paste" user "Package Geometry/Pastemask Top")
		(15 "B.Paste" user "Package Geometry/Pastemask Bottom")
		(5 "F.SilkS" user "Ref Des/Silkscreen Top")
		(7 "B.SilkS" user "Ref Des/Silkscreen Bottom")
		(1 "F.Mask" user "Board Geometry/Soldermask Top")
		(3 "B.Mask" user "Board Geometry/Soldermask Bottom")
		(17 "Dwgs.User" user "User.Drawings")
		(19 "Cmts.User" user "User.Comments")
		(21 "Eco1.User" user "User.Eco1")
		(23 "Eco2.User" user "User.Eco2")
		(25 "Edge.Cuts" user "Board Geometry/Outline")
		(27 "Margin" user)
		(31 "F.CrtYd" user "Package Geometry/Place Bound Top")
		(29 "B.CrtYd" user "Package Geometry/Place Bound Bottom")
		(35 "F.Fab" user "Ref Des/Assembly Top")
		(33 "B.Fab" user "Ref Des/Assembly Bottom")
	)
	(footprint ""
		(layer "F.Cu")
		(at 11.572494 -256.413)
		(property "Reference" "C2073"
			(at 0 0 0)
			(layer "F.SilkS")
			(hide yes)
			(effects
				(font
					(size 1.27 1.27)
				)
			)
		)
		(property "Value" ""
			(at 0 0 0)
			(layer "F.Fab")
			(effects
				(font
					(size 1.27 1.27)
				)
			)
		)
		(duplicate_pad_numbers_are_jumpers no)
		(fp_line
			(start -0.7874 -0.4064)
			(end 0.7874 -0.4064)
			(stroke
				(width 0.1524)
				(type default)
			)
			(layer "F.SilkS")
		)
		(fp_line
			(start -0.7874 0.4064)
			(end -0.7874 -0.4064)
			(stroke
				(width 0.1524)
				(type default)
			)
			(layer "F.SilkS")
		)
		(fp_line
			(start 0.7874 -0.4064)
			(end 0.7874 0.4064)
			(stroke
				(width 0.1524)
				(type default)
			)
			(layer "F.SilkS")
		)
		(fp_line
			(start 0.7874 0.4064)
			(end -0.7874 0.4064)
			(stroke
				(width 0.1524)
				(type default)
			)
			(layer "F.SilkS")
		)
		(fp_line
			(start -0.67945 -0.305054)
			(end -0.12065 -0.305054)
			(stroke
				(width 0.1)
				(type default)
			)
			(layer "F.Fab")
		)
		(fp_line
			(start -0.67945 0.3048)
			(end -0.67945 -0.305054)
			(stroke
				(width 0.1)
				(type default)
			)
			(layer "F.Fab")
		)
		(fp_line
			(start -0.12065 -0.305054)
			(end -0.12065 -0.2794)
			(stroke
				(width 0.1)
				(type default)
			)
			(layer "F.Fab")
		)
		(fp_line
			(start -0.12065 -0.2794)
			(end 0.12065 -0.2794)
			(stroke
				(width 0.1)
				(type default)
			)
			(layer "F.Fab")
		)
		(fp_line
			(start -0.12065 0.2794)
			(end -0.12065 0.3048)
			(stroke
				(width 0.1)
				(type default)
			)
			(layer "F.Fab")
		)
		(fp_line
			(start -0.12065 0.3048)
			(end -0.67945 0.3048)
			(stroke
				(width 0.1)
				(type default)
			)
			(layer "F.Fab")
		)
		(fp_line
			(start 0.120396 0.2794)
			(end -0.12065 0.2794)
			(stroke
				(width 0.1)
				(type default)
			)
			(layer "F.Fab")
		)
		(fp_line
			(start 0.120396 0.3048)
			(end 0.120396 0.2794)
			(stroke
				(width 0.1)
				(type default)
			)
			(layer "F.Fab")
		)
		(fp_line
			(start 0.12065 -0.3048)
			(end 0.67945 -0.3048)
			(stroke
				(width 0.1)
				(type default)
			)
			(layer "F.Fab")
		)
		(fp_line
			(start 0.12065 -0.2794)
			(end 0.12065 -0.3048)
			(stroke
				(width 0.1)
				(type default)
			)
			(layer "F.Fab")
		)
		(fp_line
			(start 0.67945 -0.3048)
			(end 0.67945 0.3048)
			(stroke
				(width 0.1)
				(type default)
			)
			(layer "F.Fab")
		)
		(fp_line
			(start 0.67945 0.3048)
			(end 0.120396 0.3048)
			(stroke
				(width 0.1)
				(type default)
			)
			(layer "F.Fab")
		)
		(pad "1" smd circle
			(at -0.40005 0)
			(size 0 0)
			(layers "F.Cu" "F.Mask" "F.Paste")
			(net "P3V3_AUX")
		)
		(pad "2" smd circle
			(at 0.40005 0)
			(size 0 0)
			(layers "F.Cu" "F.Mask" "F.Paste")
			(net "GND")
		)
	)
	(footprint ""
		(layer "F.Cu")
		(at 15.113 -114.427 -90)
		(property "Reference" "R5364"
			(at 0 0 270)
			(layer "F.SilkS")
			(hide yes)
			(effects
				(font
					(size 1.27 1.27)
				)
			)
		)
		(property "Value" ""
			(at 0 0 270)
			(layer "F.Fab")
			(effects
				(font
					(size 1.27 1.27)
				)
			)
		)
		(duplicate_pad_numbers_are_jumpers no)
		(fp_line
			(start -0.7874 0.4064)
			(end -0.7874 -0.4064)
			(stroke
				(width 0.1524)
				(type default)
			)
			(layer "F.SilkS")
		)
		(fp_line
			(start 0.7874 0.4064)
			(end -0.7874 0.4064)
			(stroke
				(width 0.1524)
				(type default)
			)
			(layer "F.SilkS")
		)
		(fp_line
			(start -0.7874 -0.4064)
			(end 0.7874 -0.4064)
			(stroke
				(width 0.1524)
				(type default)
			)
			(layer "F.SilkS")
		)
		(fp_line
			(start 0.7874 -0.4064)
			(end 0.7874 0.4064)
			(stroke
				(width 0.1524)
				(type default)
			)
			(layer "F.SilkS")
		)
		(fp_line
			(start -0.67945 0.3048)
			(end -0.67945 -0.305054)
			(stroke
				(width 0.1)
				(type default)
			)
			(layer "F.Fab")
		)
		(fp_line
			(start -0.12065 0.3048)
			(end -0.67945 0.3048)
			(stroke
				(width 0.1)
				(type default)
			)
			(layer "F.Fab")
		)
		(fp_line
			(start 0.120396 0.3048)
			(end 0.120396 0.2794)
			(stroke
				(width 0.1)
				(type default)
			)
			(layer "F.Fab")
		)
		(fp_line
			(start 0.67945 0.3048)
			(end 0.120396 0.3048)
			(stroke
				(width 0.1)
				(type default)
			)
			(layer "F.Fab")
		)
		(fp_line
			(start -0.12065 0.2794)
			(end -0.12065 0.3048)
			(stroke
				(width 0.1)
				(type default)
			)
			(layer "F.Fab")
		)
		(fp_line
			(start 0.120396 0.2794)
			(end -0.12065 0.2794)
			(stroke
				(width 0.1)
				(type default)
			)
			(layer "F.Fab")
		)
		(fp_line
			(start -0.12065 -0.2794)
			(end 0.12065 -0.2794)
			(stroke
				(width 0.1)
				(type default)
			)
			(layer "F.Fab")
		)
		(fp_line
			(start 0.12065 -0.2794)
			(end 0.12065 -0.3048)
			(stroke
				(width 0.1)
				(type default)
			)
			(layer "F.Fab")
		)
		(fp_line
			(start 0.12065 -0.3048)
			(end 0.67945 -0.3048)
			(stroke
				(width 0.1)
				(type default)
			)
			(layer "F.Fab")
		)
		(fp_line
			(start 0.67945 -0.3048)
			(end 0.67945 0.3048)
			(stroke
				(width 0.1)
				(type default)
			)
			(layer "F.Fab")
		)
		(fp_line
			(start -0.67945 -0.305054)
			(end -0.12065 -0.305054)
			(stroke
				(width 0.1)
				(type default)
			)
			(layer "F.Fab")
		)
		(fp_line
			(start -0.12065 -0.305054)
			(end -0.12065 -0.2794)
			(stroke
				(width 0.1)
				(type default)
			)
			(layer "F.Fab")
		)
		(pad "1" smd rect
			(at -0.40005 0 90)
			(size 0.4572 0.508)
			(layers "F.Cu" "F.Mask" "F.Paste")
			(net "FAN_5_OK_LED_R_N")
		)
		(pad "2" smd rect
			(at 0.40005 0 90)
			(size 0.4572 0.508)
			(layers "F.Cu" "F.Mask" "F.Paste")
			(net "FAN_5_OK_R_LED_N")
		)
	)
	(footprint ""
		(layer "F.Cu")
		(at 17.033494 -255.905 -90)
		(property "Reference" "C2072"
			(at 0 0 270)
			(layer "F.SilkS")
			(hide yes)
			(effects
				(font
					(size 1.27 1.27)
				)
			)
		)
		(property "Value" ""
			(at 0 0 270)
			(layer "F.Fab")
			(effects
				(font
					(size 1.27 1.27)
				)
			)
		)
		(duplicate_pad_numbers_are_jumpers no)
		(fp_line
			(start -0.7874 0.4064)
			(end -0.7874 -0.4064)
			(stroke
				(width 0.1524)
				(type default)
			)
			(layer "F.SilkS")
		)
		(fp_line
			(start 0.7874 0.4064)
			(end -0.7874 0.4064)
			(stroke
				(width 0.1524)
				(type default)
			)
			(layer "F.SilkS")
		)
		(fp_line
			(start -0.7874 -0.4064)
			(end 0.7874 -0.4064)
			(stroke
				(width 0.1524)
				(type default)
			)
			(layer "F.SilkS")
		)
		(fp_line
			(start 0.7874 -0.4064)
			(end 0.7874 0.4064)
			(stroke
				(width 0.1524)
				(type default)
			)
			(layer "F.SilkS")
		)
		(fp_line
			(start -0.67945 0.3048)
			(end -0.67945 -0.305054)
			(stroke
				(width 0.1)
				(type default)
			)
			(layer "F.Fab")
		)
		(fp_line
			(start -0.12065 0.3048)
			(end -0.67945 0.3048)
			(stroke
				(width 0.1)
				(type default)
			)
			(layer "F.Fab")
		)
		(fp_line
			(start 0.120396 0.3048)
			(end 0.120396 0.2794)
			(stroke
				(width 0.1)
				(type default)
			)
			(layer "F.Fab")
		)
		(fp_line
			(start 0.67945 0.3048)
			(end 0.120396 0.3048)
			(stroke
				(width 0.1)
				(type default)
			)
			(layer "F.Fab")
		)
		(fp_line
			(start -0.12065 0.2794)
			(end -0.12065 0.3048)
			(stroke
				(width 0.1)
				(type default)
			)
			(layer "F.Fab")
		)
		(fp_line
			(start 0.120396 0.2794)
			(end -0.12065 0.2794)
			(stroke
				(width 0.1)
				(type default)
			)
			(layer "F.Fab")
		)
		(fp_line
			(start -0.12065 -0.2794)
			(end 0.12065 -0.2794)
			(stroke
				(width 0.1)
				(type default)
			)
			(layer "F.Fab")
		)
		(fp_line
			(start 0.12065 -0.2794)
			(end 0.12065 -0.3048)
			(stroke
				(width 0.1)
				(type default)
			)
			(layer "F.Fab")
		)
		(fp_line
			(start 0.12065 -0.3048)
			(end 0.67945 -0.3048)
			(stroke
				(width 0.1)
				(type default)
			)
			(layer "F.Fab")
		)
		(fp_line
			(start 0.67945 -0.3048)
			(end 0.67945 0.3048)
			(stroke
				(width 0.1)
				(type default)
			)
			(layer "F.Fab")
		)
		(fp_line
			(start -0.67945 -0.305054)
			(end -0.12065 -0.305054)
			(stroke
				(width 0.1)
				(type default)
			)
			(layer "F.Fab")
		)
		(fp_line
			(start -0.12065 -0.305054)
			(end -0.12065 -0.2794)
			(stroke
				(width 0.1)
				(type default)
			)
			(layer "F.Fab")
		)
		(pad "1" smd circle
			(at -0.40005 0 270)
			(size 0 0)
			(layers "F.Cu" "F.Mask" "F.Paste")
			(net "P3V3_AUX")
		)
		(pad "2" smd circle
			(at 0.40005 0 270)
			(size 0 0)
			(layers "F.Cu" "F.Mask" "F.Paste")
			(net "GND")
		)
	)
	(footprint ""
		(layer "F.Cu")
		(at 22.479 -25.654 90)
		(property "Reference" "U66"
			(at -0.762 -1.75133 90)
			(unlocked yes)
			(layer "F.SilkS")
			(effects
				(font
					(size 0.7874 0.5842)
					(thickness 0.1524)
				)
				(justify left)
			)
		)
		(property "Value" ""
			(at 0 0 90)
			(layer "F.Fab")
			(effects
				(font
					(size 1.27 1.27)
				)
			)
		)
		(duplicate_pad_numbers_are_jumpers no)
		(fp_line
			(start 1.33096 -1.100074)
			(end 1.33096 1.100074)
			(stroke
				(width 0.1524)
				(type default)
			)
			(layer "F.SilkS")
		)
		(fp_line
			(start 0.381 -1.100074)
			(end 1.33096 -1.100074)
			(stroke
				(width 0.1524)
				(type default)
			)
			(layer "F.SilkS")
		)
		(fp_line
			(start -0.381 -1.100074)
			(end 0 -0.649986)
			(stroke
				(width 0.1524)
				(type default)
			)
			(layer "F.SilkS")
		)
		(fp_line
			(start -1.33096 -1.100074)
			(end -0.381 -1.100074)
			(stroke
				(width 0.1524)
				(type default)
			)
			(layer "F.SilkS")
		)
		(fp_line
			(start 0 -0.649986)
			(end 0.381 -1.100074)
			(stroke
				(width 0.1524)
				(type default)
			)
			(layer "F.SilkS")
		)
		(fp_line
			(start 1.33096 1.100074)
			(end -1.33096 1.100074)
			(stroke
				(width 0.1524)
				(type default)
			)
			(layer "F.SilkS")
		)
		(fp_line
			(start -1.33096 1.100074)
			(end -1.33096 -1.100074)
			(stroke
				(width 0.1524)
				(type default)
			)
			(layer "F.SilkS")
		)
		(fp_poly
			(pts
				(xy -1.884934 -1.383792) (xy -2.24409 -1.024636) (xy -1.525524 -0.665226)
			)
			(stroke
				(width 0)
				(type default)
			)
			(fill yes)
			(layer "F.SilkS")
		)
		(fp_line
			(start 0.674878 -1.100074)
			(end 0.674878 1.100074)
			(stroke
				(width 0.1)
				(type default)
			)
			(layer "F.Fab")
		)
		(fp_line
			(start -0.674878 -1.100074)
			(end 0.674878 -1.100074)
			(stroke
				(width 0.1)
				(type default)
			)
			(layer "F.Fab")
		)
		(fp_line
			(start 0.674878 1.100074)
			(end -0.674878 1.100074)
			(stroke
				(width 0.1)
				(type default)
			)
			(layer "F.Fab")
		)
		(fp_line
			(start -0.674878 1.100074)
			(end -0.674878 -1.100074)
			(stroke
				(width 0.1)
				(type default)
			)
			(layer "F.Fab")
		)
		(fp_poly
			(pts
				(xy -2.209292 -0.902462) (xy -2.209292 -0.394462) (xy -1.447292 -0.648462)
			)
			(stroke
				(width 0)
				(type default)
			)
			(fill yes)
			(layer "F.Fab")
		)
		(pad "1" smd rect
			(at -0.94996 -0.649986 180)
			(size 0.4064 0.508)
			(layers "F.Cu" "F.Mask" "F.Paste")
			(net "NC_U66_P1")
		)
		(pad "2" smd rect
			(at -0.94996 0 180)
			(size 0.4064 0.508)
			(layers "F.Cu" "F.Mask" "F.Paste")
			(net "FAN_3_PWM")
		)
		(pad "3" smd rect
			(at -0.94996 0.649986 180)
			(size 0.4064 0.508)
			(layers "F.Cu" "F.Mask" "F.Paste")
			(net "GND")
		)
		(pad "4" smd rect
			(at 0.94996 0.649986 180)
			(size 0.4064 0.508)
			(layers "F.Cu" "F.Mask" "F.Paste")
			(net "FAN_3_PWM_BUF")
		)
		(pad "5" smd rect
			(at 0.94996 -0.649986 180)
			(size 0.4064 0.508)
			(layers "F.Cu" "F.Mask" "F.Paste")
			(net "P3V3_AUX")
		)
	)
	(footprint ""
		(layer "F.Cu")
		(at 14.097 -98.552 90)
		(property "Reference" "R5667"
			(at 0 0 90)
			(layer "F.SilkS")
			(hide yes)
			(effects
				(font
					(size 1.27 1.27)
				)
			)
		)
		(property "Value" ""
			(at 0 0 90)
			(layer "F.Fab")
			(effects
				(font
					(size 1.27 1.27)
				)
			)
		)
		(duplicate_pad_numbers_are_jumpers no)
		(fp_line
			(start 0.7874 -0.4064)
			(end 0.7874 0.4064)
			(stroke
				(width 0.1524)
				(type default)
			)
			(layer "F.SilkS")
		)
		(fp_line
			(start -0.7874 -0.4064)
			(end 0.7874 -0.4064)
			(stroke
				(width 0.1524)
				(type default)
			)
			(layer "F.SilkS")
		)
		(fp_line
			(start 0.7874 0.4064)
			(end -0.7874 0.4064)
			(stroke
				(width 0.1524)
				(type default)
			)
			(layer "F.SilkS")
		)
		(fp_line
			(start -0.7874 0.4064)
			(end -0.7874 -0.4064)
			(stroke
				(width 0.1524)
				(type default)
			)
			(layer "F.SilkS")
		)
		(fp_line
			(start -0.12065 -0.305054)
			(end -0.12065 -0.2794)
			(stroke
				(width 0.1)
				(type default)
			)
			(layer "F.Fab")
		)
		(fp_line
			(start -0.67945 -0.305054)
			(end -0.12065 -0.305054)
			(stroke
				(width 0.1)
				(type default)
			)
			(layer "F.Fab")
		)
		(fp_line
			(start 0.67945 -0.3048)
			(end 0.67945 0.3048)
			(stroke
				(width 0.1)
				(type default)
			)
			(layer "F.Fab")
		)
		(fp_line
			(start 0.12065 -0.3048)
			(end 0.67945 -0.3048)
			(stroke
				(width 0.1)
				(type default)
			)
			(layer "F.Fab")
		)
		(fp_line
			(start 0.12065 -0.2794)
			(end 0.12065 -0.3048)
			(stroke
				(width 0.1)
				(type default)
			)
			(layer "F.Fab")
		)
		(fp_line
			(start -0.12065 -0.2794)
			(end 0.12065 -0.2794)
			(stroke
				(width 0.1)
				(type default)
			)
			(layer "F.Fab")
		)
		(fp_line
			(start 0.120396 0.2794)
			(end -0.12065 0.2794)
			(stroke
				(width 0.1)
				(type default)
			)
			(layer "F.Fab")
		)
		(fp_line
			(start -0.12065 0.2794)
			(end -0.12065 0.3048)
			(stroke
				(width 0.1)
				(type default)
			)
			(layer "F.Fab")
		)
		(fp_line
			(start 0.67945 0.3048)
			(end 0.120396 0.3048)
			(stroke
				(width 0.1)
				(type default)
			)
			(layer "F.Fab")
		)
		(fp_line
			(start 0.120396 0.3048)
			(end 0.120396 0.2794)
			(stroke
				(width 0.1)
				(type default)
			)
			(layer "F.Fab")
		)
		(fp_line
			(start -0.12065 0.3048)
			(end -0.67945 0.3048)
			(stroke
				(width 0.1)
				(type default)
			)
			(layer "F.Fab")
		)
		(fp_line
			(start -0.67945 0.3048)
			(end -0.67945 -0.305054)
			(stroke
				(width 0.1)
				(type default)
			)
			(layer "F.Fab")
		)
		(pad "1" smd circle
			(at -0.40005 0 90)
			(size 0 0)
			(layers "F.Cu" "F.Mask" "F.Paste")
			(net "FAN_5_PRESENT")
		)
		(pad "2" smd circle
			(at 0.40005 0 90)
			(size 0 0)
			(layers "F.Cu" "F.Mask" "F.Paste")
			(net "GND")
		)
	)
	(footprint ""
		(layer "F.Cu")
		(at 37.846 -126.238 180)
		(property "Reference" "R5606"
			(at 0 0 180)
			(layer "F.SilkS")
			(hide yes)
			(effects
				(font
					(size 1.27 1.27)
				)
			)
		)
		(property "Value" ""
			(at 0 0 180)
			(layer "F.Fab")
			(effects
				(font
					(size 1.27 1.27)
				)
			)
		)
		(duplicate_pad_numbers_are_jumpers no)
		(fp_line
			(start 0.7874 0.4064)
			(end -0.7874 0.4064)
			(stroke
				(width 0.1524)
				(type default)
			)
			(layer "F.SilkS")
		)
		(fp_line
			(start 0.7874 -0.4064)
			(end 0.7874 0.4064)
			(stroke
				(width 0.1524)
				(type default)
			)
			(layer "F.SilkS")
		)
		(fp_line
			(start -0.7874 0.4064)
			(end -0.7874 -0.4064)
			(stroke
				(width 0.1524)
				(type default)
			)
			(layer "F.SilkS")
		)
		(fp_line
			(start -0.7874 -0.4064)
			(end 0.7874 -0.4064)
			(stroke
				(width 0.1524)
				(type default)
			)
			(layer "F.SilkS")
		)
		(fp_line
			(start 0.67945 0.3048)
			(end 0.120396 0.3048)
			(stroke
				(width 0.1)
				(type default)
			)
			(layer "F.Fab")
		)
		(fp_line
			(start 0.67945 -0.3048)
			(end 0.67945 0.3048)
			(stroke
				(width 0.1)
				(type default)
			)
			(layer "F.Fab")
		)
		(fp_line
			(start 0.12065 -0.2794)
			(end 0.12065 -0.3048)
			(stroke
				(width 0.1)
				(type default)
			)
			(layer "F.Fab")
		)
		(fp_line
			(start 0.12065 -0.3048)
			(end 0.67945 -0.3048)
			(stroke
				(width 0.1)
				(type default)
			)
			(layer "F.Fab")
		)
		(fp_line
			(start 0.120396 0.3048)
			(end 0.120396 0.2794)
			(stroke
				(width 0.1)
				(type default)
			)
			(layer "F.Fab")
		)
		(fp_line
			(start 0.120396 0.2794)
			(end -0.12065 0.2794)
			(stroke
				(width 0.1)
				(type default)
			)
			(layer "F.Fab")
		)
		(fp_line
			(start -0.12065 0.3048)
			(end -0.67945 0.3048)
			(stroke
				(width 0.1)
				(type default)
			)
			(layer "F.Fab")
		)
		(fp_line
			(start -0.12065 0.2794)
			(end -0.12065 0.3048)
			(stroke
				(width 0.1)
				(type default)
			)
			(layer "F.Fab")
		)
		(fp_line
			(start -0.12065 -0.2794)
			(end 0.12065 -0.2794)
			(stroke
				(width 0.1)
				(type default)
			)
			(layer "F.Fab")
		)
		(fp_line
			(start -0.12065 -0.305054)
			(end -0.12065 -0.2794)
			(stroke
				(width 0.1)
				(type default)
			)
			(layer "F.Fab")
		)
		(fp_line
			(start -0.67945 0.3048)
			(end -0.67945 -0.305054)
			(stroke
				(width 0.1)
				(type default)
			)
			(layer "F.Fab")
		)
		(fp_line
			(start -0.67945 -0.305054)
			(end -0.12065 -0.305054)
			(stroke
				(width 0.1)
				(type default)
			)
			(layer "F.Fab")
		)
		(pad "1" smd rect
			(at -0.40005 0)
			(size 0.4572 0.508)
			(layers "F.Cu" "F.Mask" "F.Paste")
			(net "FAN_2_TACH_OL")
		)
		(pad "2" smd rect
			(at 0.40005 0)
			(size 0.4572 0.508)
			(layers "F.Cu" "F.Mask" "F.Paste")
			(net "FAN_2_TACH_OL_R1")
		)
	)
)
